# BASEBOARD_FAB2 (Tioga Pass) — schematic netlist excerpt (pin names and nets, part order shuffled) for the footprints in the layout excerpt that follows; sources: Cadence DE-HDL packaged netlist, KiCad conversion of Wiwynn_Tioga_Pass_MB.brd

R2U6  RES  20.0 1% CHIP  pkg 0402  page 138 : A = SMB_LAN_STBY_LVC3_SCL_R1 ; B = SMB_LAN_STBY_LVC3_SCL
C7A29  CAP  220PF 50V 10% X7R  pkg 0402LF  page 218 : A = A_TSENSE_PVDDQ_DEF ; B = GND
C1B20  CAP  1.0UF 16V 10% X6S  pkg 0402  page 227 : A = VR_PVDDQ_KLM_PH1_VCIN ; B = GND

(kicad_pcb
	(version 20260206)
	(generator "pcbnew")
	(generator_version "10.0")
	(general
		(thickness 1.6)
		(legacy_teardrops no)
	)
	(paper "A4")
	(title_block
		(title "Wiwynn_Tioga_Pass_MB.brd")
		(comment 1 "Tioga Pass / footprints 141-143 of 4770")
	)
	(layers
		(0 "F.Cu" signal "TOP")
		(4 "In1.Cu" signal "L2GND")
		(6 "In2.Cu" signal "L3")
		(8 "In3.Cu" signal "L4GND")
		(10 "In4.Cu" signal "L5")
		(12 "In5.Cu" signal "L6GND")
		(14 "In6.Cu" signal "L7VCC")
		(16 "In7.Cu" signal "L8VCC")
		(18 "In8.Cu" signal "L9GND")
		(20 "In9.Cu" signal "L10")
		(22 "In10.Cu" signal "L11GND")
		(24 "In11.Cu" signal "L12")
		(26 "In12.Cu" signal "L13GND")
		(2 "B.Cu" signal "BOTTOM")
		(9 "F.Adhes" user "F.Adhesive")
		(11 "B.Adhes" user "B.Adhesive")
		(13 "F.Paste" user "Package Geometry/Pastemask Top")
		(15 "B.Paste" user "Package Geometry/Pastemask Bottom")
		(5 "F.SilkS" user "Ref Des/Silkscreen Top")
		(7 "B.SilkS" user "Ref Des/Silkscreen Bottom")
		(1 "F.Mask" user "Board Geometry/Soldermask Top")
		(3 "B.Mask" user "Board Geometry/Soldermask Bottom")
		(17 "Dwgs.User" user "User.Drawings")
		(19 "Cmts.User" user "User.Comments")
		(21 "Eco1.User" user "User.Eco1")
		(23 "Eco2.User" user "User.Eco2")
		(25 "Edge.Cuts" user "Board Geometry/Outline")
		(27 "Margin" user)
		(31 "F.CrtYd" user "Package Geometry/Place Bound Top")
		(29 "B.CrtYd" user "Package Geometry/Place Bound Bottom")
		(35 "F.Fab" user "Ref Des/Assembly Top")
		(33 "B.Fab" user "Ref Des/Assembly Bottom")
	)
	(footprint ""
		(layer "F.Cu")
		(at 395.351 -88.2015)
		(property "Reference" "R2U6"
			(at 0 0 0)
			(layer "F.SilkS")
			(hide yes)
			(effects
				(font
					(size 1.27 1.27)
				)
			)
		)
		(property "Value" ""
			(at 0 0 0)
			(layer "F.Fab")
			(effects
				(font
					(size 1.27 1.27)
				)
			)
		)
		(duplicate_pad_numbers_are_jumpers no)
		(fp_poly
			(pts
				(xy -0.2794 -0.1016) (xy 0.2794 -0.1016) (xy 0.2794 0.9906) (xy -0.2794 0.9906)
			)
			(stroke
				(width 0)
				(type default)
			)
			(fill no)
			(layer "F.CrtYd")
		)
		(fp_line
			(start -0.2794 -0.1016)
			(end -0.2794 0.9906)
			(stroke
				(width 0.1)
				(type default)
			)
			(layer "F.Fab")
		)
		(fp_line
			(start -0.2794 0.9906)
			(end 0.2794 0.9906)
			(stroke
				(width 0.1)
				(type default)
			)
			(layer "F.Fab")
		)
		(fp_line
			(start 0.2794 -0.1016)
			(end -0.2794 -0.1016)
			(stroke
				(width 0.1)
				(type default)
			)
			(layer "F.Fab")
		)
		(fp_line
			(start 0.2794 0.9906)
			(end 0.2794 -0.1016)
			(stroke
				(width 0.1)
				(type default)
			)
			(layer "F.Fab")
		)
		(pad "1" smd rect
			(at 0 0)
			(size 0.508 0.508)
			(layers "F.Cu" "F.Mask" "F.Paste")
			(net "SMB_LAN_STBY_LVC3_SCL_R1")
		)
		(pad "2" smd rect
			(at 0 0.889)
			(size 0.508 0.508)
			(layers "F.Cu" "F.Mask" "F.Paste")
			(net "SMB_LAN_STBY_LVC3_SCL")
		)
		(zone
			(layer "F.Cu")
			(hatch none 0.5)
			(connect_pads
				(clearance 0)
			)
			(min_thickness 0.25)
			(keepout
				(tracks allowed)
				(vias not_allowed)
				(pads allowed)
				(copperpour not_allowed)
				(footprints allowed)
			)
			(placement
				(enabled no)
				(sheetname "")
			)
			(fill
				(thermal_gap 0.5)
				(thermal_bridge_width 0.5)
				(island_removal_mode 0)
			)
			(polygon
				(pts
					(xy 395.097 -87.9475) (xy 395.605 -87.9475) (xy 395.605 -87.5665) (xy 395.097 -87.5665)
				)
			)
		)
		(zone
			(layer "F.Cu")
			(hatch none 0.5)
			(connect_pads
				(clearance 0)
			)
			(min_thickness 0.25)
			(keepout
				(tracks not_allowed)
				(vias allowed)
				(pads allowed)
				(copperpour not_allowed)
				(footprints allowed)
			)
			(placement
				(enabled no)
				(sheetname "")
			)
			(fill
				(thermal_gap 0.5)
				(thermal_bridge_width 0.5)
				(island_removal_mode 0)
			)
			(polygon
				(pts
					(xy 395.097 -87.5665) (xy 395.605 -87.5665) (xy 395.605 -87.9475) (xy 395.097 -87.9475)
				)
			)
		)
	)
	(footprint ""
		(layer "F.Cu")
		(at 354.89769 -139.965176 -90)
		(property "Reference" "C7A29"
			(at 0 0 270)
			(layer "F.SilkS")
			(hide yes)
			(effects
				(font
					(size 1.27 1.27)
				)
			)
		)
		(property "Value" ""
			(at 0 0 270)
			(layer "F.Fab")
			(effects
				(font
					(size 1.27 1.27)
				)
			)
		)
		(duplicate_pad_numbers_are_jumpers no)
		(fp_rect
			(start 0.3048 0.9906)
			(end -0.3048 -0.1016)
			(stroke
				(width 0)
				(type default)
			)
			(fill no)
			(layer "F.CrtYd")
		)
		(fp_line
			(start -0.3048 0.9906)
			(end 0.3048 0.9906)
			(stroke
				(width 0.1)
				(type default)
			)
			(layer "F.Fab")
		)
		(fp_line
			(start 0.3048 0.9906)
			(end 0.3048 -0.1016)
			(stroke
				(width 0.1)
				(type default)
			)
			(layer "F.Fab")
		)
		(fp_line
			(start -0.3048 -0.1016)
			(end -0.3048 0.9906)
			(stroke
				(width 0.1)
				(type default)
			)
			(layer "F.Fab")
		)
		(fp_line
			(start 0.3048 -0.1016)
			(end -0.3048 -0.1016)
			(stroke
				(width 0.1)
				(type default)
			)
			(layer "F.Fab")
		)
		(pad "1" smd rect
			(at 0 0 270)
			(size 0.508 0.508)
			(layers "F.Cu" "F.Mask" "F.Paste")
			(net "A_TSENSE_PVDDQ_DEF")
		)
		(pad "2" smd rect
			(at 0 0.889 270)
			(size 0.508 0.508)
			(layers "F.Cu" "F.Mask" "F.Paste")
			(net "GND")
		)
		(zone
			(layer "F.Cu")
			(hatch none 0.5)
			(connect_pads
				(clearance 0)
			)
			(min_thickness 0.25)
			(keepout
				(tracks not_allowed)
				(vias allowed)
				(pads allowed)
				(copperpour not_allowed)
				(footprints allowed)
			)
			(placement
				(enabled no)
				(sheetname "")
			)
			(fill
				(thermal_gap 0.5)
				(thermal_bridge_width 0.5)
				(island_removal_mode 0)
			)
			(polygon
				(pts
					(xy 354.26269 -139.711176) (xy 354.64369 -139.711176) (xy 354.64369 -140.219176) (xy 354.26269 -140.219176)
				)
			)
		)
		(zone
			(layer "F.Cu")
			(hatch none 0.5)
			(connect_pads
				(clearance 0)
			)
			(min_thickness 0.25)
			(keepout
				(tracks allowed)
				(vias not_allowed)
				(pads allowed)
				(copperpour not_allowed)
				(footprints allowed)
			)
			(placement
				(enabled no)
				(sheetname "")
			)
			(fill
				(thermal_gap 0.5)
				(thermal_bridge_width 0.5)
				(island_removal_mode 0)
			)
			(polygon
				(pts
					(xy 354.26269 -139.711176) (xy 354.64369 -139.711176) (xy 354.64369 -140.219176) (xy 354.26269 -140.219176)
				)
			)
		)
	)
	(footprint ""
		(layer "F.Cu")
		(at 0.889 -134.3152 -90)
		(property "Reference" "C1B20"
			(at 0 0 270)
			(layer "F.SilkS")
			(hide yes)
			(effects
				(font
					(size 1.27 1.27)
				)
			)
		)
		(property "Value" ""
			(at 0 0 270)
			(layer "F.Fab")
			(effects
				(font
					(size 1.27 1.27)
				)
			)
		)
		(duplicate_pad_numbers_are_jumpers no)
		(fp_poly
			(pts
				(xy 0.3048 -0.1016) (xy 0.3048 0.9906) (xy -0.3048 0.9906) (xy -0.3048 -0.1016)
			)
			(stroke
				(width 0)
				(type default)
			)
			(fill no)
			(layer "F.CrtYd")
		)
		(fp_line
			(start -0.3048 0.9906)
			(end 0.3048 0.9906)
			(stroke
				(width 0.1)
				(type default)
			)
			(layer "F.Fab")
		)
		(fp_line
			(start 0.3048 0.9906)
			(end 0.3048 -0.1016)
			(stroke
				(width 0.1)
				(type default)
			)
			(layer "F.Fab")
		)
		(fp_line
			(start -0.3048 -0.1016)
			(end -0.3048 0.9906)
			(stroke
				(width 0.1)
				(type default)
			)
			(layer "F.Fab")
		)
		(fp_line
			(start 0.3048 -0.1016)
			(end -0.3048 -0.1016)
			(stroke
				(width 0.1)
				(type default)
			)
			(layer "F.Fab")
		)
		(pad "1" smd rect
			(at 0 0 270)
			(size 0.508 0.508)
			(layers "F.Cu" "F.Mask" "F.Paste")
			(net "VR_PVDDQ_KLM_PH1_VCIN")
		)
		(pad "2" smd rect
			(at 0 0.889 270)
			(size 0.508 0.508)
			(layers "F.Cu" "F.Mask" "F.Paste")
			(net "GND")
		)
		(zone
			(layer "F.Cu")
			(hatch none 0.5)
			(connect_pads
				(clearance 0)
			)
			(min_thickness 0.25)
			(keepout
				(tracks not_allowed)
				(vias allowed)
				(pads allowed)
				(copperpour not_allowed)
				(footprints allowed)
			)
			(placement
				(enabled no)
				(sheetname "")
			)
			(fill
				(thermal_gap 0.5)
				(thermal_bridge_width 0.5)
				(island_removal_mode 0)
			)
			(polygon
				(pts
					(xy 0.254 -134.5692) (xy 0.254 -134.0612) (xy 0.635 -134.0612) (xy 0.635 -134.5692)
				)
			)
		)
		(zone
			(layer "F.Cu")
			(hatch none 0.5)
			(connect_pads
				(clearance 0)
			)
			(min_thickness 0.25)
			(keepout
				(tracks allowed)
				(vias not_allowed)
				(pads allowed)
				(copperpour not_allowed)
				(footprints allowed)
			)
			(placement
				(enabled no)
				(sheetname "")
			)
			(fill
				(thermal_gap 0.5)
				(thermal_bridge_width 0.5)
				(island_removal_mode 0)
			)
			(polygon
				(pts
					(xy 0.635 -134.5692) (xy 0.635 -134.0612) (xy 0.254 -134.0612) (xy 0.254 -134.5692)
				)
			)
		)
	)
)
